(kicad_pcb
	(version 20260206)
	(generator "pcbnew")
	(generator_version "10.0")
	(general
		(thickness 1.6)
		(legacy_teardrops no)
	)
	(paper "A4")
	(title_block
		(title "01162023_DA0F0TEBIF0_F0T_Expander_BD_F_brd_V02_OCP.brd")
		(comment 1 "Grand Teton / footprint 290 of 9728 (J5), pads 78-142 of 142")
	)
	(layers
		(0 "F.Cu" signal "TOP")
		(4 "In1.Cu" signal "GND")
		(6 "In2.Cu" signal "VCC")
		(8 "In3.Cu" signal "VCC1")
		(10 "In4.Cu" signal "GND1")
		(12 "In5.Cu" signal "IN1")
		(14 "In6.Cu" signal "GND2")
		(16 "In7.Cu" signal "IN2")
		(18 "In8.Cu" signal "GND3")
		(20 "In9.Cu" signal "IN3")
		(22 "In10.Cu" signal "GND4")
		(24 "In11.Cu" signal "IN4")
		(26 "In12.Cu" signal "GND5")
		(28 "In13.Cu" signal "IN5")
		(30 "In14.Cu" signal "GND6")
		(32 "In15.Cu" signal "IN6")
		(34 "In16.Cu" signal "GND7")
		(2 "B.Cu" signal "BOTTOM")
		(9 "F.Adhes" user "F.Adhesive")
		(11 "B.Adhes" user "B.Adhesive")
		(13 "F.Paste" user "Package Geometry/Pastemask Top")
		(15 "B.Paste" user "Package Geometry/Pastemask Bottom")
		(5 "F.SilkS" user "Ref Des/Silkscreen Top")
		(7 "B.SilkS" user "Ref Des/Silkscreen Bottom")
		(1 "F.Mask" user "Board Geometry/Soldermask Top")
		(3 "B.Mask" user "Board Geometry/Soldermask Bottom")
		(17 "Dwgs.User" user "User.Drawings")
		(19 "Cmts.User" user "User.Comments")
		(21 "Eco1.User" user "User.Eco1")
		(23 "Eco2.User" user "User.Eco2")
		(25 "Edge.Cuts" user "Board Geometry/Outline")
		(27 "Margin" user)
		(31 "F.CrtYd" user "Package Geometry/Place Bound Top")
		(29 "B.CrtYd" user "Package Geometry/Place Bound Bottom")
		(35 "F.Fab" user "Ref Des/Assembly Top")
		(33 "B.Fab" user "Ref Des/Assembly Bottom")
	)
	(footprint ""
		(layer "F.Cu")
		(at 159.910018 -412.090108)
		(property "Reference" "J5"
			(at -6.04647 3.572764 90)
			(unlocked yes)
			(layer "F.SilkS")
			(effects
				(font
					(size 2.032 1.524)
					(thickness 0.1524)
				)
				(justify left)
			)
		)
		(property "Value" ""
			(at 0 0 0)
			(layer "F.Fab")
			(effects
				(font
					(size 1.27 1.27)
				)
			)
		)
		(duplicate_pad_numbers_are_jumpers no)
		(pad "N2_3" thru_hole circle
			(at 4.400042 27.29992 180)
			(size 0.906272 0.906272)
			(drill 0.499872)
			(layers "*.Cu" "*.Mask")
			(remove_unused_layers no)
			(net "GND")
			(clearance 0.0508)
			(thermal_gap 0.0508)
		)
		(pad "N2_5" thru_hole circle
			(at 8.800084 27.29992 180)
			(size 0.906272 0.906272)
			(drill 0.499872)
			(layers "*.Cu" "*.Mask")
			(remove_unused_layers no)
			(net "GND")
			(clearance 0.0508)
			(thermal_gap 0.0508)
		)
		(pad "N2_7" thru_hole circle
			(at 13.199872 27.29992 180)
			(size 0.906272 0.906272)
			(drill 0.499872)
			(layers "*.Cu" "*.Mask")
			(remove_unused_layers no)
			(net "GND")
			(clearance 0.0508)
			(thermal_gap 0.0508)
		)
		(pad "N2_9" thru_hole circle
			(at 17.599914 27.29992 180)
			(size 0.906272 0.906272)
			(drill 0.499872)
			(layers "*.Cu" "*.Mask")
			(remove_unused_layers no)
			(net "GND")
			(clearance 0.0508)
			(thermal_gap 0.0508)
		)
		(pad "N10" thru_hole circle
			(at 19.800062 27.500072 180)
			(size 0.71628 0.71628)
			(drill 0.30988)
			(layers "*.Cu" "*.Mask")
			(remove_unused_layers no)
			(net "Net_8835")
			(clearance 0.0508)
			(thermal_gap 0.0508)
		)
		(pad "O9" thru_hole circle
			(at 17.599914 28.599892 180)
			(size 0.71628 0.71628)
			(drill 0.30988)
			(layers "*.Cu" "*.Mask")
			(remove_unused_layers no)
			(net "Net_8833")
			(clearance 0.0508)
			(thermal_gap 0.0508)
		)
		(pad "O10" thru_hole circle
			(at 19.800062 28.800044 180)
			(size 0.71628 0.71628)
			(drill 0.30988)
			(layers "*.Cu" "*.Mask")
			(remove_unused_layers no)
			(net "Net_8834")
			(clearance 0.0508)
			(thermal_gap 0.0508)
		)
		(pad "P2" thru_hole circle
			(at 2.199894 30.100016 180)
			(size 0.906272 0.906272)
			(drill 0.499872)
			(layers "*.Cu" "*.Mask")
			(remove_unused_layers no)
			(net "GND")
			(clearance 0.0508)
			(thermal_gap 0.0508)
		)
		(pad "P4" thru_hole circle
			(at 6.599936 30.100016 180)
			(size 0.906272 0.906272)
			(drill 0.499872)
			(layers "*.Cu" "*.Mask")
			(remove_unused_layers no)
			(net "GND")
			(clearance 0.0508)
			(thermal_gap 0.0508)
		)
		(pad "P6" thru_hole circle
			(at 10.999978 30.100016 180)
			(size 0.906272 0.906272)
			(drill 0.499872)
			(layers "*.Cu" "*.Mask")
			(remove_unused_layers no)
			(net "GND")
			(clearance 0.0508)
			(thermal_gap 0.0508)
		)
		(pad "P8" thru_hole circle
			(at 15.40002 30.100016 180)
			(size 0.906272 0.906272)
			(drill 0.499872)
			(layers "*.Cu" "*.Mask")
			(remove_unused_layers no)
			(net "GND")
			(clearance 0.0508)
			(thermal_gap 0.0508)
		)
		(pad "P9" thru_hole circle
			(at 17.599914 29.900118 180)
			(size 0.71628 0.71628)
			(drill 0.30988)
			(layers "*.Cu" "*.Mask")
			(remove_unused_layers no)
			(net "Net_8832")
			(clearance 0.0508)
			(thermal_gap 0.0508)
		)
		(pad "P10" thru_hole circle
			(at 19.800062 30.100016 180)
			(size 0.906272 0.906272)
			(drill 0.499872)
			(layers "*.Cu" "*.Mask")
			(remove_unused_layers no)
			(net "GND")
			(clearance 0.0508)
			(thermal_gap 0.0508)
		)
		(pad "Q1" thru_hole circle
			(at 0 31.20009 180)
			(size 0.906272 0.906272)
			(drill 0.499872)
			(layers "*.Cu" "*.Mask")
			(remove_unused_layers no)
			(net "GND")
			(clearance 0.0508)
			(thermal_gap 0.0508)
		)
		(pad "Q3" thru_hole circle
			(at 4.400042 31.20009 180)
			(size 0.906272 0.906272)
			(drill 0.499872)
			(layers "*.Cu" "*.Mask")
			(remove_unused_layers no)
			(net "GND")
			(clearance 0.0508)
			(thermal_gap 0.0508)
		)
		(pad "Q5" thru_hole circle
			(at 8.800084 31.20009 180)
			(size 0.906272 0.906272)
			(drill 0.499872)
			(layers "*.Cu" "*.Mask")
			(remove_unused_layers no)
			(net "GND")
			(clearance 0.0508)
			(thermal_gap 0.0508)
		)
		(pad "Q7" thru_hole circle
			(at 13.199872 31.20009 180)
			(size 0.906272 0.906272)
			(drill 0.499872)
			(layers "*.Cu" "*.Mask")
			(remove_unused_layers no)
			(net "GND")
			(clearance 0.0508)
			(thermal_gap 0.0508)
		)
		(pad "Q9" thru_hole circle
			(at 17.599914 31.20009 180)
			(size 0.906272 0.906272)
			(drill 0.499872)
			(layers "*.Cu" "*.Mask")
			(remove_unused_layers no)
			(net "GND")
			(clearance 0.0508)
			(thermal_gap 0.0508)
		)
		(pad "Q10" thru_hole circle
			(at 19.800062 31.399988 180)
			(size 0.71628 0.71628)
			(drill 0.30988)
			(layers "*.Cu" "*.Mask")
			(remove_unused_layers no)
			(net "Net_8831")
			(clearance 0.0508)
			(thermal_gap 0.0508)
		)
		(pad "R9" thru_hole circle
			(at 17.599914 32.500062 180)
			(size 0.71628 0.71628)
			(drill 0.30988)
			(layers "*.Cu" "*.Mask")
			(remove_unused_layers no)
			(net "Net_8829")
			(clearance 0.0508)
			(thermal_gap 0.0508)
		)
		(pad "R10" thru_hole circle
			(at 19.800062 32.69996 180)
			(size 0.71628 0.71628)
			(drill 0.30988)
			(layers "*.Cu" "*.Mask")
			(remove_unused_layers no)
			(net "Net_8830")
			(clearance 0.0508)
			(thermal_gap 0.0508)
		)
		(pad "S2" thru_hole circle
			(at 2.199894 33.999932 180)
			(size 0.906272 0.906272)
			(drill 0.499872)
			(layers "*.Cu" "*.Mask")
			(remove_unused_layers no)
			(net "GND")
			(clearance 0.0508)
			(thermal_gap 0.0508)
		)
		(pad "S4" thru_hole circle
			(at 6.599936 33.999932 180)
			(size 0.906272 0.906272)
			(drill 0.499872)
			(layers "*.Cu" "*.Mask")
			(remove_unused_layers no)
			(net "GND")
			(clearance 0.0508)
			(thermal_gap 0.0508)
		)
		(pad "S6" thru_hole circle
			(at 10.999978 33.999932 180)
			(size 0.906272 0.906272)
			(drill 0.499872)
			(layers "*.Cu" "*.Mask")
			(remove_unused_layers no)
			(net "GND")
			(clearance 0.0508)
			(thermal_gap 0.0508)
		)
		(pad "S8" thru_hole circle
			(at 15.40002 33.999932 180)
			(size 0.906272 0.906272)
			(drill 0.499872)
			(layers "*.Cu" "*.Mask")
			(remove_unused_layers no)
			(net "GND")
			(clearance 0.0508)
			(thermal_gap 0.0508)
		)
		(pad "S9" thru_hole circle
			(at 17.599914 33.800034 180)
			(size 0.71628 0.71628)
			(drill 0.30988)
			(layers "*.Cu" "*.Mask")
			(remove_unused_layers no)
			(net "Net_8828")
			(clearance 0.0508)
			(thermal_gap 0.0508)
		)
		(pad "S10" thru_hole circle
			(at 19.800062 33.999932 180)
			(size 0.906272 0.906272)
			(drill 0.499872)
			(layers "*.Cu" "*.Mask")
			(remove_unused_layers no)
			(net "GND")
			(clearance 0.0508)
			(thermal_gap 0.0508)
		)
		(pad "T1" thru_hole circle
			(at 0 35.100006 180)
			(size 0.906272 0.906272)
			(drill 0.499872)
			(layers "*.Cu" "*.Mask")
			(remove_unused_layers no)
			(net "GND")
			(clearance 0.0508)
			(thermal_gap 0.0508)
		)
		(pad "T3" thru_hole circle
			(at 4.400042 35.100006 180)
			(size 0.906272 0.906272)
			(drill 0.499872)
			(layers "*.Cu" "*.Mask")
			(remove_unused_layers no)
			(net "GND")
			(clearance 0.0508)
			(thermal_gap 0.0508)
		)
		(pad "T5" thru_hole circle
			(at 8.800084 35.100006 180)
			(size 0.906272 0.906272)
			(drill 0.499872)
			(layers "*.Cu" "*.Mask")
			(remove_unused_layers no)
			(net "GND")
			(clearance 0.0508)
			(thermal_gap 0.0508)
		)
		(pad "T7" thru_hole circle
			(at 13.199872 35.100006 180)
			(size 0.906272 0.906272)
			(drill 0.499872)
			(layers "*.Cu" "*.Mask")
			(remove_unused_layers no)
			(net "GND")
			(clearance 0.0508)
			(thermal_gap 0.0508)
		)
		(pad "T9" thru_hole circle
			(at 17.599914 35.100006 180)
			(size 0.906272 0.906272)
			(drill 0.499872)
			(layers "*.Cu" "*.Mask")
			(remove_unused_layers no)
			(net "GND")
			(clearance 0.0508)
			(thermal_gap 0.0508)
		)
		(pad "T10" thru_hole circle
			(at 19.800062 35.299904 180)
			(size 0.71628 0.71628)
			(drill 0.30988)
			(layers "*.Cu" "*.Mask")
			(remove_unused_layers no)
			(net "Net_8827")
			(clearance 0.0508)
			(thermal_gap 0.0508)
		)
		(pad "U9" thru_hole circle
			(at 17.599914 36.399978 180)
			(size 0.71628 0.71628)
			(drill 0.30988)
			(layers "*.Cu" "*.Mask")
			(remove_unused_layers no)
			(net "Net_8825")
			(clearance 0.0508)
			(thermal_gap 0.0508)
		)
		(pad "U10" thru_hole circle
			(at 19.800062 36.599876 180)
			(size 0.71628 0.71628)
			(drill 0.30988)
			(layers "*.Cu" "*.Mask")
			(remove_unused_layers no)
			(net "Net_8826")
			(clearance 0.0508)
			(thermal_gap 0.0508)
		)
		(pad "V2" thru_hole circle
			(at 2.199894 37.900102 180)
			(size 0.906272 0.906272)
			(drill 0.499872)
			(layers "*.Cu" "*.Mask")
			(remove_unused_layers no)
			(net "GND")
			(clearance 0.0508)
			(thermal_gap 0.0508)
		)
		(pad "V4" thru_hole circle
			(at 6.599936 37.900102 180)
			(size 0.906272 0.906272)
			(drill 0.499872)
			(layers "*.Cu" "*.Mask")
			(remove_unused_layers no)
			(net "GND")
			(clearance 0.0508)
			(thermal_gap 0.0508)
		)
		(pad "V6" thru_hole circle
			(at 10.999978 37.900102 180)
			(size 0.906272 0.906272)
			(drill 0.499872)
			(layers "*.Cu" "*.Mask")
			(remove_unused_layers no)
			(net "GND")
			(clearance 0.0508)
			(thermal_gap 0.0508)
		)
		(pad "V8" thru_hole circle
			(at 15.40002 37.900102 180)
			(size 0.906272 0.906272)
			(drill 0.499872)
			(layers "*.Cu" "*.Mask")
			(remove_unused_layers no)
			(net "GND")
			(clearance 0.0508)
			(thermal_gap 0.0508)
		)
		(pad "V9" thru_hole circle
			(at 17.599914 37.69995 180)
			(size 0.71628 0.71628)
			(drill 0.30988)
			(layers "*.Cu" "*.Mask")
			(remove_unused_layers no)
			(net "Net_8824")
			(clearance 0.0508)
			(thermal_gap 0.0508)
		)
		(pad "V10" thru_hole circle
			(at 19.800062 37.900102 180)
			(size 0.906272 0.906272)
			(drill 0.499872)
			(layers "*.Cu" "*.Mask")
			(remove_unused_layers no)
			(net "GND")
			(clearance 0.0508)
			(thermal_gap 0.0508)
		)
		(pad "W1" thru_hole circle
			(at 0 38.999922 180)
			(size 0.906272 0.906272)
			(drill 0.499872)
			(layers "*.Cu" "*.Mask")
			(remove_unused_layers no)
			(net "GND")
			(clearance 0.0508)
			(thermal_gap 0.0508)
		)
		(pad "W3" thru_hole circle
			(at 4.400042 38.999922 180)
			(size 0.906272 0.906272)
			(drill 0.499872)
			(layers "*.Cu" "*.Mask")
			(remove_unused_layers no)
			(net "GND")
			(clearance 0.0508)
			(thermal_gap 0.0508)
		)
		(pad "W5" thru_hole circle
			(at 8.800084 38.999922 180)
			(size 0.906272 0.906272)
			(drill 0.499872)
			(layers "*.Cu" "*.Mask")
			(remove_unused_layers no)
			(net "GND")
			(clearance 0.0508)
			(thermal_gap 0.0508)
		)
		(pad "W7" thru_hole circle
			(at 13.199872 38.999922 180)
			(size 0.906272 0.906272)
			(drill 0.499872)
			(layers "*.Cu" "*.Mask")
			(remove_unused_layers no)
			(net "GND")
			(clearance 0.0508)
			(thermal_gap 0.0508)
		)
		(pad "W9" thru_hole circle
			(at 17.599914 38.999922 180)
			(size 0.906272 0.906272)
			(drill 0.499872)
			(layers "*.Cu" "*.Mask")
			(remove_unused_layers no)
			(net "GND")
			(clearance 0.0508)
			(thermal_gap 0.0508)
		)
		(pad "W10" thru_hole circle
			(at 19.800062 39.200074 180)
			(size 0.71628 0.71628)
			(drill 0.30988)
			(layers "*.Cu" "*.Mask")
			(remove_unused_layers no)
			(net "Net_8823")
			(clearance 0.0508)
			(thermal_gap 0.0508)
		)
		(pad "X9" thru_hole circle
			(at 17.599914 40.299894 180)
			(size 0.71628 0.71628)
			(drill 0.30988)
			(layers "*.Cu" "*.Mask")
			(remove_unused_layers no)
			(net "Net_8821")
			(clearance 0.0508)
			(thermal_gap 0.0508)
		)
		(pad "X10" thru_hole circle
			(at 19.800062 40.500046 180)
			(size 0.71628 0.71628)
			(drill 0.30988)
			(layers "*.Cu" "*.Mask")
			(remove_unused_layers no)
			(net "Net_8822")
			(clearance 0.0508)
			(thermal_gap 0.0508)
		)
		(pad "Y2" thru_hole circle
			(at 2.199894 41.800018 180)
			(size 0.906272 0.906272)
			(drill 0.499872)
			(layers "*.Cu" "*.Mask")
			(remove_unused_layers no)
			(net "GND")
			(clearance 0.0508)
			(thermal_gap 0.0508)
		)
		(pad "Y4" thru_hole circle
			(at 6.599936 41.800018 180)
			(size 0.906272 0.906272)
			(drill 0.499872)
			(layers "*.Cu" "*.Mask")
			(remove_unused_layers no)
			(net "GND")
			(clearance 0.0508)
			(thermal_gap 0.0508)
		)
		(pad "Y6" thru_hole circle
			(at 10.999978 41.800018 180)
			(size 0.906272 0.906272)
			(drill 0.499872)
			(layers "*.Cu" "*.Mask")
			(remove_unused_layers no)
			(net "GND")
			(clearance 0.0508)
			(thermal_gap 0.0508)
		)
		(pad "Y8" thru_hole circle
			(at 15.40002 41.800018 180)
			(size 0.906272 0.906272)
			(drill 0.499872)
			(layers "*.Cu" "*.Mask")
			(remove_unused_layers no)
			(net "GND")
			(clearance 0.0508)
			(thermal_gap 0.0508)
		)
		(pad "Y9" thru_hole circle
			(at 17.599914 41.60012 180)
			(size 0.71628 0.71628)
			(drill 0.30988)
			(layers "*.Cu" "*.Mask")
			(remove_unused_layers no)
			(net "Net_8820")
			(clearance 0.0508)
			(thermal_gap 0.0508)
		)
		(pad "Y10" thru_hole circle
			(at 19.800062 41.800018 180)
			(size 0.906272 0.906272)
			(drill 0.499872)
			(layers "*.Cu" "*.Mask")
			(remove_unused_layers no)
			(net "GND")
			(clearance 0.0508)
			(thermal_gap 0.0508)
		)
		(pad "Z1" thru_hole circle
			(at 0 42.900092 180)
			(size 0.906272 0.906272)
			(drill 0.499872)
			(layers "*.Cu" "*.Mask")
			(remove_unused_layers no)
			(net "GND")
			(clearance 0.0508)
			(thermal_gap 0.0508)
		)
		(pad "Z2" thru_hole circle
			(at 2.199894 43.09999 180)
			(size 0.71628 0.71628)
			(drill 0.30988)
			(layers "*.Cu" "*.Mask")
			(remove_unused_layers no)
			(net "GPU_FPGA_EROT_FATALERR_N")
			(clearance 0.0508)
			(thermal_gap 0.0508)
		)
		(pad "Z3" thru_hole circle
			(at 4.400042 42.900092 180)
			(size 0.906272 0.906272)
			(drill 0.499872)
			(layers "*.Cu" "*.Mask")
			(remove_unused_layers no)
			(net "GND")
			(clearance 0.0508)
			(thermal_gap 0.0508)
		)
		(pad "Z4" thru_hole circle
			(at 6.599936 43.09999 180)
			(size 0.71628 0.71628)
			(drill 0.30988)
			(layers "*.Cu" "*.Mask")
			(remove_unused_layers no)
			(net "GPU_3V3IO_RSVD0_FFU")
			(clearance 0.0508)
			(thermal_gap 0.0508)
		)
		(pad "Z5" thru_hole circle
			(at 8.800084 42.900092 180)
			(size 0.906272 0.906272)
			(drill 0.499872)
			(layers "*.Cu" "*.Mask")
			(remove_unused_layers no)
			(net "GND")
			(clearance 0.0508)
			(thermal_gap 0.0508)
		)
		(pad "Z6" thru_hole circle
			(at 10.999978 43.09999 180)
			(size 0.71628 0.71628)
			(drill 0.30988)
			(layers "*.Cu" "*.Mask")
			(remove_unused_layers no)
			(net "GPU_3V3IO_RSVD1_FFU")
			(clearance 0.0508)
			(thermal_gap 0.0508)
		)
		(pad "Z7" thru_hole circle
			(at 13.199872 42.900092 180)
			(size 0.906272 0.906272)
			(drill 0.499872)
			(layers "*.Cu" "*.Mask")
			(remove_unused_layers no)
			(net "GND")
			(clearance 0.0508)
			(thermal_gap 0.0508)
		)
		(pad "Z8" thru_hole circle
			(at 15.40002 43.09999 180)
			(size 0.71628 0.71628)
			(drill 0.30988)
			(layers "*.Cu" "*.Mask")
			(remove_unused_layers no)
			(net "PRSNT_GPU_A3_N")
			(clearance 0.0508)
			(thermal_gap 0.0508)
		)
		(pad "Z9" thru_hole circle
			(at 17.599914 42.900092 180)
			(size 0.906272 0.906272)
			(drill 0.499872)
			(layers "*.Cu" "*.Mask")
			(remove_unused_layers no)
			(net "GND")
			(clearance 0.0508)
			(thermal_gap 0.0508)
		)
		(pad "Z10" thru_hole circle
			(at 19.800062 43.09999 180)
			(size 0.71628 0.71628)
			(drill 0.30988)
			(layers "*.Cu" "*.Mask")
			(remove_unused_layers no)
			(net "RST_GPU_FPGA_EROT_R_N")
			(clearance 0.0508)
			(thermal_gap 0.0508)
		)
	)
)
